# BASEBOARD_FAB2 (Tioga Pass) — schematic netlist excerpt (pin names and nets, part order shuffled) for the footprints in the layout excerpt that follows; sources: Cadence DE-HDL packaged netlist, KiCad conversion of Wiwynn_Tioga_Pass_MB.brd

C3L29  SC1U10V2KX-4-GP  10%  pkg SMD-BCG6  page 236 : \1\ = P5V_STBY ; \2\ = GND
R2L10  RES  1.5K 1% CHIP  pkg 0402  page 235 : A = VR_PVNN_PCH_VINSEN ; B = GND
R9M9  RES  0.0 5% CHIP  pkg 0402  page 226 : A = FM_PVDDQ_KLM_EN ; B = VR_PVDDQ_KLM_VREN

(kicad_pcb
	(version 20260206)
	(generator "pcbnew")
	(generator_version "10.0")
	(general
		(thickness 1.6)
		(legacy_teardrops no)
	)
	(paper "A4")
	(title_block
		(title "Wiwynn_Tioga_Pass_MB.brd")
		(comment 1 "Tioga Pass / footprints 4164-4166 of 4770")
	)
	(layers
		(0 "F.Cu" signal "TOP")
		(4 "In1.Cu" signal "L2GND")
		(6 "In2.Cu" signal "L3")
		(8 "In3.Cu" signal "L4GND")
		(10 "In4.Cu" signal "L5")
		(12 "In5.Cu" signal "L6GND")
		(14 "In6.Cu" signal "L7VCC")
		(16 "In7.Cu" signal "L8VCC")
		(18 "In8.Cu" signal "L9GND")
		(20 "In9.Cu" signal "L10")
		(22 "In10.Cu" signal "L11GND")
		(24 "In11.Cu" signal "L12")
		(26 "In12.Cu" signal "L13GND")
		(2 "B.Cu" signal "BOTTOM")
		(9 "F.Adhes" user "F.Adhesive")
		(11 "B.Adhes" user "B.Adhesive")
		(13 "F.Paste" user "Package Geometry/Pastemask Top")
		(15 "B.Paste" user "Package Geometry/Pastemask Bottom")
		(5 "F.SilkS" user "Ref Des/Silkscreen Top")
		(7 "B.SilkS" user "Ref Des/Silkscreen Bottom")
		(1 "F.Mask" user "Board Geometry/Soldermask Top")
		(3 "B.Mask" user "Board Geometry/Soldermask Bottom")
		(17 "Dwgs.User" user "User.Drawings")
		(19 "Cmts.User" user "User.Comments")
		(21 "Eco1.User" user "User.Eco1")
		(23 "Eco2.User" user "User.Eco2")
		(25 "Edge.Cuts" user "Board Geometry/Outline")
		(27 "Margin" user)
		(31 "F.CrtYd" user "Package Geometry/Place Bound Top")
		(29 "B.CrtYd" user "Package Geometry/Place Bound Bottom")
		(35 "F.Fab" user "Ref Des/Assembly Top")
		(33 "B.Fab" user "Ref Des/Assembly Bottom")
	)
	(footprint ""
		(layer "B.Cu")
		(at 391.56894 -152.00122 -90)
		(property "Reference" "R2L10"
			(at 0 0 90)
			(layer "B.SilkS")
			(hide yes)
			(effects
				(font
					(size 1.27 1.27)
				)
				(justify mirror)
			)
		)
		(property "Value" ""
			(at 0 0 90)
			(layer "B.Fab")
			(effects
				(font
					(size 1.27 1.27)
				)
				(justify mirror)
			)
		)
		(duplicate_pad_numbers_are_jumpers no)
		(fp_poly
			(pts
				(xy 0.2794 -0.1016) (xy -0.2794 -0.1016) (xy -0.2794 0.9906) (xy 0.2794 0.9906)
			)
			(stroke
				(width 0)
				(type default)
			)
			(fill no)
			(layer "B.CrtYd")
		)
		(fp_line
			(start -0.2794 0.9906)
			(end -0.2794 -0.1016)
			(stroke
				(width 0.1)
				(type default)
			)
			(layer "B.Fab")
		)
		(fp_line
			(start 0.2794 0.9906)
			(end -0.2794 0.9906)
			(stroke
				(width 0.1)
				(type default)
			)
			(layer "B.Fab")
		)
		(fp_line
			(start -0.2794 -0.1016)
			(end 0.2794 -0.1016)
			(stroke
				(width 0.1)
				(type default)
			)
			(layer "B.Fab")
		)
		(fp_line
			(start 0.2794 -0.1016)
			(end 0.2794 0.9906)
			(stroke
				(width 0.1)
				(type default)
			)
			(layer "B.Fab")
		)
		(pad "1" smd rect
			(at 0 0 90)
			(size 0.508 0.508)
			(layers "B.Cu" "B.Mask" "B.Paste")
			(net "VR_PVNN_PCH_VINSEN")
		)
		(pad "2" smd rect
			(at 0 0.889 90)
			(size 0.508 0.508)
			(layers "B.Cu" "B.Mask" "B.Paste")
			(net "GND")
		)
		(zone
			(layer "B.Cu")
			(hatch none 0.5)
			(connect_pads
				(clearance 0)
			)
			(min_thickness 0.25)
			(keepout
				(tracks not_allowed)
				(vias allowed)
				(pads allowed)
				(copperpour not_allowed)
				(footprints allowed)
			)
			(placement
				(enabled no)
				(sheetname "")
			)
			(fill
				(thermal_gap 0.5)
				(thermal_bridge_width 0.5)
				(island_removal_mode 0)
			)
			(polygon
				(pts
					(xy 390.93394 -151.74722) (xy 390.93394 -152.25522) (xy 391.31494 -152.25522) (xy 391.31494 -151.74722)
				)
			)
		)
		(zone
			(layer "B.Cu")
			(hatch none 0.5)
			(connect_pads
				(clearance 0)
			)
			(min_thickness 0.25)
			(keepout
				(tracks allowed)
				(vias not_allowed)
				(pads allowed)
				(copperpour not_allowed)
				(footprints allowed)
			)
			(placement
				(enabled no)
				(sheetname "")
			)
			(fill
				(thermal_gap 0.5)
				(thermal_bridge_width 0.5)
				(island_removal_mode 0)
			)
			(polygon
				(pts
					(xy 391.31494 -151.74722) (xy 391.31494 -152.25522) (xy 390.93394 -152.25522) (xy 390.93394 -151.74722)
				)
			)
		)
	)
	(footprint ""
		(layer "B.Cu")
		(at 382.176274 -153.328624)
		(property "Reference" "C3L29"
			(at 0 0 0)
			(layer "B.SilkS")
			(hide yes)
			(effects
				(font
					(size 1.27 1.27)
				)
				(justify mirror)
			)
		)
		(property "Value" "*"
			(at -1.1811 -2.8194 0)
			(unlocked yes)
			(layer "B.Fab")
			(hide yes)
			(effects
				(font
					(size 1.27 1.016)
					(thickness 0.1524)
				)
				(justify mirror)
			)
		)
		(property "Device Type" "SC1U10V2KX-4-GP_SMD-BCG6-SC1U1A"
			(at -1.1811 -4.3434 0)
			(unlocked yes)
			(layer "B.Fab")
			(hide yes)
			(effects
				(font
					(size 1.27 1.016)
					(thickness 0.1524)
				)
				(justify mirror)
			)
		)
		(duplicate_pad_numbers_are_jumpers no)
		(fp_rect
			(start 0.4318 0.9525)
			(end -0.4318 -0.9525)
			(stroke
				(width 0)
				(type default)
			)
			(fill no)
			(layer "B.CrtYd")
		)
		(fp_rect
			(start 0.4318 0.9525)
			(end -0.4318 -0.9525)
			(stroke
				(width 0)
				(type default)
			)
			(fill no)
			(layer "B.Fab")
		)
		(pad "1" smd custom
			(at 0 -0.4445 180)
			(size 0.1524 0.1524)
			(layers "B.Cu" "B.Mask" "B.Paste")
			(net "P5V_STBY")
			(options
				(clearance outline)
				(anchor circle)
			)
			(primitives
				(gr_poly
					(pts
						(arc
							(start 0.3048 0.2032)
							(mid 0.275042 0.275042)
							(end 0.2032 0.3048)
						)
						(arc
							(start -0.2032 0.3048)
							(mid -0.275042 0.275042)
							(end -0.3048 0.2032)
						)
						(arc
							(start -0.3048 -0.2032)
							(mid -0.275042 -0.275042)
							(end -0.2032 -0.3048)
						)
						(arc
							(start 0.2032 -0.3048)
							(mid 0.275042 -0.275042)
							(end 0.3048 -0.2032)
						)
					)
					(width 0)
					(fill yes)
				)
			)
		)
		(pad "2" smd custom
			(at 0 0.4445 180)
			(size 0.1524 0.1524)
			(layers "B.Cu" "B.Mask" "B.Paste")
			(net "GND")
			(options
				(clearance outline)
				(anchor circle)
			)
			(primitives
				(gr_poly
					(pts
						(arc
							(start 0.3048 0.2032)
							(mid 0.275042 0.275042)
							(end 0.2032 0.3048)
						)
						(arc
							(start -0.2032 0.3048)
							(mid -0.275042 0.275042)
							(end -0.3048 0.2032)
						)
						(arc
							(start -0.3048 -0.2032)
							(mid -0.275042 -0.275042)
							(end -0.2032 -0.3048)
						)
						(arc
							(start 0.2032 -0.3048)
							(mid 0.275042 -0.275042)
							(end 0.3048 -0.2032)
						)
					)
					(width 0)
					(fill yes)
				)
			)
		)
	)
	(footprint ""
		(layer "B.Cu")
		(at -0.889 -132.334)
		(property "Reference" "R9M9"
			(at 0 0 0)
			(layer "B.SilkS")
			(hide yes)
			(effects
				(font
					(size 1.27 1.27)
				)
				(justify mirror)
			)
		)
		(property "Value" ""
			(at 0 0 0)
			(layer "B.Fab")
			(effects
				(font
					(size 1.27 1.27)
				)
				(justify mirror)
			)
		)
		(duplicate_pad_numbers_are_jumpers no)
		(fp_poly
			(pts
				(xy 0.2794 -0.1016) (xy -0.2794 -0.1016) (xy -0.2794 0.9906) (xy 0.2794 0.9906)
			)
			(stroke
				(width 0)
				(type default)
			)
			(fill no)
			(layer "B.CrtYd")
		)
		(fp_line
			(start -0.2794 -0.1016)
			(end 0.2794 -0.1016)
			(stroke
				(width 0.1)
				(type default)
			)
			(layer "B.Fab")
		)
		(fp_line
			(start -0.2794 0.9906)
			(end -0.2794 -0.1016)
			(stroke
				(width 0.1)
				(type default)
			)
			(layer "B.Fab")
		)
		(fp_line
			(start 0.2794 -0.1016)
			(end 0.2794 0.9906)
			(stroke
				(width 0.1)
				(type default)
			)
			(layer "B.Fab")
		)
		(fp_line
			(start 0.2794 0.9906)
			(end -0.2794 0.9906)
			(stroke
				(width 0.1)
				(type default)
			)
			(layer "B.Fab")
		)
		(pad "1" smd rect
			(at 0 0 180)
			(size 0.508 0.508)
			(layers "B.Cu" "B.Mask" "B.Paste")
			(net "FM_PVDDQ_KLM_EN")
		)
		(pad "2" smd rect
			(at 0 0.889 180)
			(size 0.508 0.508)
			(layers "B.Cu" "B.Mask" "B.Paste")
			(net "VR_PVDDQ_KLM_VREN")
		)
		(zone
			(layer "B.Cu")
			(hatch none 0.5)
			(connect_pads
				(clearance 0)
			)
			(min_thickness 0.25)
			(keepout
				(tracks allowed)
				(vias not_allowed)
				(pads allowed)
				(copperpour not_allowed)
				(footprints allowed)
			)
			(placement
				(enabled no)
				(sheetname "")
			)
			(fill
				(thermal_gap 0.5)
				(thermal_bridge_width 0.5)
				(island_removal_mode 0)
			)
			(polygon
				(pts
					(xy -0.635 -132.08) (xy -1.143 -132.08) (xy -1.143 -131.699) (xy -0.635 -131.699)
				)
			)
		)
		(zone
			(layer "B.Cu")
			(hatch none 0.5)
			(connect_pads
				(clearance 0)
			)
			(min_thickness 0.25)
			(keepout
				(tracks not_allowed)
				(vias allowed)
				(pads allowed)
				(copperpour not_allowed)
				(footprints allowed)
			)
			(placement
				(enabled no)
				(sheetname "")
			)
			(fill
				(thermal_gap 0.5)
				(thermal_bridge_width 0.5)
				(island_removal_mode 0)
			)
			(polygon
				(pts
					(xy -0.635 -131.699) (xy -1.143 -131.699) (xy -1.143 -132.08) (xy -0.635 -132.08)
				)
			)
		)
	)
)
